# S9S_MB_2U (Grand Teton) — schematic netlist excerpt (pin names and nets, part order shuffled) for the footprints in the layout excerpt that follows; sources: Cadence DE-HDL packaged netlist, KiCad conversion of 03242023_DA0F0TMBIJ0_F0T_Motherboard_J_brd_V01_OCP.brd

X13  TP_TDR_4P_FTS  TP_TDR_4P_DIP EMPTY  pkg TH  page 309
  S1  = TDR_DIFF_100_TOP_DP
  P1  = T1_GND
  P2  = T1_GND
  S2  = TDR_DIFF_100_TOP_DN

R3156  Q_RES  33.2 1% CHIP  pkg 0402LF  page 164 : A = SMB_PEHPCPU1_LVC3_SCL ; B = SMB_PEHPCPU1_LVC3_R3_SCL

(kicad_pcb
	(version 20260206)
	(generator "pcbnew")
	(generator_version "10.0")
	(general
		(thickness 1.6)
		(legacy_teardrops no)
	)
	(paper "A4")
	(title_block
		(title "03242023_DA0F0TMBIJ0_F0T_Motherboard_J_brd_V01_OCP.brd")
		(comment 1 "Grand Teton / footprints 2922-2923 of 6105")
	)
	(layers
		(0 "F.Cu" signal "TOP")
		(4 "In1.Cu" signal "GND")
		(6 "In2.Cu" signal "IN1")
		(8 "In3.Cu" signal "GND1")
		(10 "In4.Cu" signal "IN2")
		(12 "In5.Cu" signal "GND2")
		(14 "In6.Cu" signal "IN3")
		(16 "In7.Cu" signal "GND3")
		(18 "In8.Cu" signal "VCC")
		(20 "In9.Cu" signal "VCC1")
		(22 "In10.Cu" signal "GND4")
		(24 "In11.Cu" signal "IN4")
		(26 "In12.Cu" signal "GND5")
		(28 "In13.Cu" signal "IN5")
		(30 "In14.Cu" signal "GND6")
		(32 "In15.Cu" signal "IN6")
		(34 "In16.Cu" signal "GND7")
		(2 "B.Cu" signal "BOTTOM")
		(9 "F.Adhes" user "F.Adhesive")
		(11 "B.Adhes" user "B.Adhesive")
		(13 "F.Paste" user "Package Geometry/Pastemask Top")
		(15 "B.Paste" user "Package Geometry/Pastemask Bottom")
		(5 "F.SilkS" user "Ref Des/Silkscreen Top")
		(7 "B.SilkS" user "Ref Des/Silkscreen Bottom")
		(1 "F.Mask" user "Board Geometry/Soldermask Top")
		(3 "B.Mask" user "Board Geometry/Soldermask Bottom")
		(17 "Dwgs.User" user "User.Drawings")
		(19 "Cmts.User" user "User.Comments")
		(21 "Eco1.User" user "User.Eco1")
		(23 "Eco2.User" user "User.Eco2")
		(25 "Edge.Cuts" user "Board Geometry/Outline")
		(27 "Margin" user)
		(31 "F.CrtYd" user "Package Geometry/Place Bound Top")
		(29 "B.CrtYd" user "Package Geometry/Place Bound Bottom")
		(35 "F.Fab" user "Ref Des/Assembly Top")
		(33 "B.Fab" user "Ref Des/Assembly Bottom")
	)
	(footprint ""
		(layer "F.Cu")
		(at 147.08378 -125.275848 180)
		(property "Reference" "R3156"
			(at 0 0 180)
			(layer "F.SilkS")
			(hide yes)
			(effects
				(font
					(size 1.27 1.27)
				)
			)
		)
		(property "Value" ""
			(at 0 0 180)
			(layer "F.Fab")
			(effects
				(font
					(size 1.27 1.27)
				)
			)
		)
		(duplicate_pad_numbers_are_jumpers no)
		(fp_line
			(start 0.7874 0.4064)
			(end -0.7874 0.4064)
			(stroke
				(width 0.1524)
				(type default)
			)
			(layer "F.SilkS")
		)
		(fp_line
			(start 0.7874 -0.4064)
			(end 0.7874 0.4064)
			(stroke
				(width 0.1524)
				(type default)
			)
			(layer "F.SilkS")
		)
		(fp_line
			(start -0.7874 0.4064)
			(end -0.7874 -0.4064)
			(stroke
				(width 0.1524)
				(type default)
			)
			(layer "F.SilkS")
		)
		(fp_line
			(start -0.7874 -0.4064)
			(end 0.7874 -0.4064)
			(stroke
				(width 0.1524)
				(type default)
			)
			(layer "F.SilkS")
		)
		(fp_line
			(start 0.67945 0.3048)
			(end 0.120396 0.3048)
			(stroke
				(width 0.1)
				(type default)
			)
			(layer "F.Fab")
		)
		(fp_line
			(start 0.67945 -0.3048)
			(end 0.67945 0.3048)
			(stroke
				(width 0.1)
				(type default)
			)
			(layer "F.Fab")
		)
		(fp_line
			(start 0.12065 -0.2794)
			(end 0.12065 -0.3048)
			(stroke
				(width 0.1)
				(type default)
			)
			(layer "F.Fab")
		)
		(fp_line
			(start 0.12065 -0.3048)
			(end 0.67945 -0.3048)
			(stroke
				(width 0.1)
				(type default)
			)
			(layer "F.Fab")
		)
		(fp_line
			(start 0.120396 0.3048)
			(end 0.120396 0.2794)
			(stroke
				(width 0.1)
				(type default)
			)
			(layer "F.Fab")
		)
		(fp_line
			(start 0.120396 0.2794)
			(end -0.12065 0.2794)
			(stroke
				(width 0.1)
				(type default)
			)
			(layer "F.Fab")
		)
		(fp_line
			(start -0.12065 0.3048)
			(end -0.67945 0.3048)
			(stroke
				(width 0.1)
				(type default)
			)
			(layer "F.Fab")
		)
		(fp_line
			(start -0.12065 0.2794)
			(end -0.12065 0.3048)
			(stroke
				(width 0.1)
				(type default)
			)
			(layer "F.Fab")
		)
		(fp_line
			(start -0.12065 -0.2794)
			(end 0.12065 -0.2794)
			(stroke
				(width 0.1)
				(type default)
			)
			(layer "F.Fab")
		)
		(fp_line
			(start -0.12065 -0.305054)
			(end -0.12065 -0.2794)
			(stroke
				(width 0.1)
				(type default)
			)
			(layer "F.Fab")
		)
		(fp_line
			(start -0.67945 0.3048)
			(end -0.67945 -0.305054)
			(stroke
				(width 0.1)
				(type default)
			)
			(layer "F.Fab")
		)
		(fp_line
			(start -0.67945 -0.305054)
			(end -0.12065 -0.305054)
			(stroke
				(width 0.1)
				(type default)
			)
			(layer "F.Fab")
		)
		(pad "1" smd circle
			(at -0.40005 0 180)
			(size 0 0)
			(layers "F.Cu" "F.Mask" "F.Paste")
			(net "SMB_PEHPCPU1_LVC3_SCL")
		)
		(pad "2" smd circle
			(at 0.40005 0 180)
			(size 0 0)
			(layers "F.Cu" "F.Mask" "F.Paste")
			(net "SMB_PEHPCPU1_LVC3_R3_SCL")
		)
	)
	(footprint ""
		(layer "F.Cu")
		(at 522.584426 2.295652 -90)
		(property "Reference" "X13"
			(at -1.331976 3.323336 90)
			(unlocked yes)
			(layer "F.SilkS")
			(effects
				(font
					(size 0.7874 0.5842)
					(thickness 0.1524)
				)
				(justify left)
			)
		)
		(property "Value" ""
			(at 0 0 270)
			(layer "F.Fab")
			(effects
				(font
					(size 1.27 1.27)
				)
			)
		)
		(property "Device Type" "TP_TDR_4P_FTS_MPKT4_H025P0200_I"
			(at 1.30175 1.27 0)
			(unlocked yes)
			(layer "F.Fab")
			(hide yes)
			(effects
				(font
					(size 0.635 0.4064)
					(thickness 0.1524)
				)
			)
		)
		(property "User Part Number" "TP15"
			(at 1.30175 1.27 0)
			(unlocked yes)
			(layer "Cmts.User")
			(hide yes)
			(effects
				(font
					(size 0.635 0.4064)
					(thickness 0.1524)
				)
			)
		)
		(duplicate_pad_numbers_are_jumpers no)
		(fp_line
			(start 0 3.81)
			(end 2.54 3.81)
			(stroke
				(width 0.1524)
				(type default)
			)
			(layer "F.SilkS")
		)
		(fp_line
			(start 2.54 3.81)
			(end 2.54 3.6703)
			(stroke
				(width 0.1524)
				(type default)
			)
			(layer "F.SilkS")
		)
		(fp_line
			(start 0 3.175)
			(end 0 3.81)
			(stroke
				(width 0.1524)
				(type default)
			)
			(layer "F.SilkS")
		)
		(fp_line
			(start 2.54 1.4097)
			(end 2.54 1.1303)
			(stroke
				(width 0.1524)
				(type default)
			)
			(layer "F.SilkS")
		)
		(fp_line
			(start 0 0.635)
			(end 0 1.905)
			(stroke
				(width 0.1524)
				(type default)
			)
			(layer "F.SilkS")
		)
		(fp_line
			(start 2.54 -1.1303)
			(end 2.54 -1.27)
			(stroke
				(width 0.1524)
				(type default)
			)
			(layer "F.SilkS")
		)
		(fp_line
			(start 0 -1.27)
			(end 0 -0.635)
			(stroke
				(width 0.1524)
				(type default)
			)
			(layer "F.SilkS")
		)
		(fp_line
			(start 2.54 -1.27)
			(end 0 -1.27)
			(stroke
				(width 0.1524)
				(type default)
			)
			(layer "F.SilkS")
		)
		(fp_poly
			(pts
				(xy -1.447292 0.108966) (xy -2.971292 0.870966) (xy -2.971292 -0.653034)
			)
			(stroke
				(width 0)
				(type default)
			)
			(fill yes)
			(layer "F.SilkS")
		)
		(fp_line
			(start 0 3.81)
			(end 2.54 3.81)
			(stroke
				(width 0.1)
				(type default)
			)
			(layer "F.Fab")
		)
		(fp_line
			(start 2.54 3.81)
			(end 2.54 -1.27)
			(stroke
				(width 0.1)
				(type default)
			)
			(layer "F.Fab")
		)
		(fp_line
			(start 0 -1.27)
			(end 0 3.81)
			(stroke
				(width 0.1)
				(type default)
			)
			(layer "F.Fab")
		)
		(fp_line
			(start 2.54 -1.27)
			(end 0 -1.27)
			(stroke
				(width 0.1)
				(type default)
			)
			(layer "F.Fab")
		)
		(fp_poly
			(pts
				(xy -0.761746 0) (xy -2.285746 -0.762) (xy -2.285746 0.762)
			)
			(stroke
				(width 0)
				(type default)
			)
			(fill yes)
			(layer "F.Fab")
		)
		(pad "1" thru_hole circle
			(at 0 0 270)
			(size 1.0033 1.0033)
			(drill 0.249936)
			(layers "*.Cu" "*.Mask")
			(remove_unused_layers no)
			(net "TDR_DIFF_100_TOP_DP")
			(clearance 0.10795)
			(thermal_gap 0.10795)
			(padstack
				(mode front_inner_back)
				(layer "Inner"
					(shape circle)
					(size 0.8001 0.8001)
					(clearance 0.1524)
				)
				(layer "B.Cu"
					(shape circle)
					(size 1.0033 1.0033)
					(clearance 0.10795)
				)
			)
		)
		(pad "2" thru_hole circle
			(at 2.54 0 270)
			(size 1.9939 1.9939)
			(drill 0.249936)
			(layers "*.Cu" "*.Mask")
			(remove_unused_layers no)
			(net "T1_GND")
			(clearance 0.10795)
			(thermal_gap 0.10795)
			(padstack
				(mode front_inner_back)
				(layer "Inner"
					(shape circle)
					(size 0.8001 0.8001)
					(clearance 0.1524)
				)
				(layer "B.Cu"
					(shape circle)
					(size 1.9939 1.9939)
					(clearance 0.10795)
				)
			)
		)
		(pad "3" thru_hole circle
			(at 2.54 2.54 270)
			(size 1.9939 1.9939)
			(drill 0.249936)
			(layers "*.Cu" "*.Mask")
			(remove_unused_layers no)
			(net "T1_GND")
			(clearance 0.10795)
			(thermal_gap 0.10795)
			(padstack
				(mode front_inner_back)
				(layer "Inner"
					(shape circle)
					(size 0.8001 0.8001)
					(clearance 0.1524)
				)
				(layer "B.Cu"
					(shape circle)
					(size 1.9939 1.9939)
					(clearance 0.10795)
				)
			)
		)
		(pad "4" thru_hole circle
			(at 0 2.54 270)
			(size 1.0033 1.0033)
			(drill 0.249936)
			(layers "*.Cu" "*.Mask")
			(remove_unused_layers no)
			(net "TDR_DIFF_100_TOP_DN")
			(clearance 0.10795)
			(thermal_gap 0.10795)
			(padstack
				(mode front_inner_back)
				(layer "Inner"
					(shape circle)
					(size 0.8001 0.8001)
					(clearance 0.1524)
				)
				(layer "B.Cu"
					(shape circle)
					(size 1.0033 1.0033)
					(clearance 0.10795)
				)
			)
		)
	)
)
